(kicad_pcb
	(version 20241229)
	(generator "pcbnew")
	(generator_version "9.0")
	(general
		(thickness 1.552)
		(legacy_teardrops no)
	)
	(paper "A4")
	(title_block
		(date "2023-07-25")
		(rev "1.1.4")
		(comment 9 "footprints 182-184 of 379")
	)
	(layers
		(0 "F.Cu" signal)
		(4 "In1.Cu" signal)
		(6 "In2.Cu" signal)
		(8 "In3.Cu" signal)
		(10 "In4.Cu" signal)
		(12 "In5.Cu" signal)
		(14 "In6.Cu" signal)
		(2 "B.Cu" signal)
		(9 "F.Adhes" user "F.Adhesive")
		(11 "B.Adhes" user "B.Adhesive")
		(13 "F.Paste" user)
		(15 "B.Paste" user)
		(5 "F.SilkS" user "F.Silkscreen")
		(7 "B.SilkS" user "B.Silkscreen")
		(1 "F.Mask" user)
		(3 "B.Mask" user)
		(17 "Dwgs.User" user "User.Drawings")
		(19 "Cmts.User" user "User.Comments")
		(21 "Eco1.User" user "User.Eco1")
		(23 "Eco2.User" user "User.Eco2")
		(25 "Edge.Cuts" user)
		(27 "Margin" user)
		(31 "F.CrtYd" user "F.Courtyard")
		(29 "B.CrtYd" user "B.Courtyard")
		(35 "F.Fab" user)
		(33 "B.Fab" user)
	)
	(footprint "antmicro-footprints:LED_0603_1608Metric_G"
		(layer "F.Cu")
		(at 105.6 73.39 90)
		(descr "LED SMD 0603 Green")
		(tags "LED SMD 0603 Green")
		(property "Reference" "D7"
			(at -2.95 -0.27 90)
			(layer "F.SilkS")
			(effects
				(font
					(size 0.65 0.65)
					(thickness 0.15)
				)
				(justify left top)
			)
		)
		(property "Value" "LED_G_0603_LTST-C190GKT"
			(at 0 1.6 90)
			(layer "F.Fab")
			(hide yes)
			(effects
				(font
					(size 0.7 0.7)
					(thickness 0.15)
				)
				(justify left top)
			)
		)
		(property "Datasheet" "https://media.digikey.com/pdf/Data%20Sheets/Lite-On%20PDFs/LTST-C190GKT.pdf"
			(at 0 0 90)
			(layer "F.Fab")
			(hide yes)
			(effects
				(font
					(size 1.27 1.27)
					(thickness 0.15)
				)
			)
		)
		(property "Description" "LED, Green, SMD, 0603, 20 mA, 2.1 V, 569 nm"
			(at 0 0 90)
			(layer "F.Fab")
			(hide yes)
			(effects
				(font
					(size 1.27 1.27)
					(thickness 0.15)
				)
			)
		)
		(property "Author" "Antmicro"
			(at 32.21 178.99 0)
			(layer "F.Fab")
			(hide yes)
			(effects
				(font
					(size 1 1)
					(thickness 0.15)
				)
			)
		)
		(property "License" "Apache-2.0"
			(at 32.21 178.99 0)
			(layer "F.Fab")
			(hide yes)
			(effects
				(font
					(size 1 1)
					(thickness 0.15)
				)
			)
		)
		(property "MPN" "LTST-C190GKT"
			(at 32.21 178.99 0)
			(layer "F.Fab")
			(hide yes)
			(effects
				(font
					(size 1 1)
					(thickness 0.15)
				)
			)
		)
		(property "Manufacturer" "Lite-On"
			(at 32.21 178.99 0)
			(layer "F.Fab")
			(hide yes)
			(effects
				(font
					(size 1 1)
					(thickness 0.15)
				)
			)
		)
		(property "Color" "Green"
			(at 0 0 90)
			(unlocked yes)
			(layer "F.Fab")
			(hide yes)
			(effects
				(font
					(size 1 1)
					(thickness 0.15)
				)
			)
		)
		(sheetname "/SDI/")
		(sheetfile "sdi.kicad_sch")
		(attr smd)
		(fp_line
			(start 0.22 -0.35)
			(end -0.22 -0.35)
			(stroke
				(width 0.15)
				(type solid)
			)
			(layer "F.SilkS")
		)
		(fp_line
			(start -1.18 -0.319)
			(end -1.18 0.321)
			(stroke
				(width 0.15)
				(type solid)
			)
			(layer "F.SilkS")
		)
		(fp_line
			(start 0.105328 0.001008)
			(end 0.24 0.001)
			(stroke
				(width 0.1)
				(type solid)
			)
			(layer "F.SilkS")
		)
		(fp_line
			(start -0.094672 0.001008)
			(end 0.105328 -0.198992)
			(stroke
				(width 0.1)
				(type solid)
			)
			(layer "F.SilkS")
		)
		(fp_line
			(start -0.094672 0.001008)
			(end -0.24 0.001008)
			(stroke
				(width 0.1)
				(type solid)
			)
			(layer "F.SilkS")
		)
		(fp_line
			(start 0.105328 0.201008)
			(end 0.105328 -0.198992)
			(stroke
				(width 0.1)
				(type solid)
			)
			(layer "F.SilkS")
		)
		(fp_line
			(start 0.105328 0.201008)
			(end -0.094672 0.001008)
			(stroke
				(width 0.1)
				(type solid)
			)
			(layer "F.SilkS")
		)
		(fp_line
			(start -0.094672 0.201008)
			(end -0.094672 -0.198992)
			(stroke
				(width 0.1)
				(type solid)
			)
			(layer "F.SilkS")
		)
		(fp_line
			(start 0.22 0.35)
			(end -0.22 0.35)
			(stroke
				(width 0.15)
				(type solid)
			)
			(layer "F.SilkS")
		)
		(fp_rect
			(start 1.25 0.65)
			(end -1.25 -0.65)
			(stroke
				(width 0.05)
				(type solid)
			)
			(fill no)
			(layer "F.CrtYd")
		)
		(fp_line
			(start 0.201 -0.202)
			(end -0.101 0)
			(stroke
				(width 0.15)
				(type solid)
			)
			(layer "F.Fab")
		)
		(fp_line
			(start -0.199 -0.202)
			(end -0.199 0.1)
			(stroke
				(width 0.15)
				(type solid)
			)
			(layer "F.Fab")
		)
		(fp_line
			(start 0.599 0)
			(end 0.201 0)
			(stroke
				(width 0.15)
				(type solid)
			)
			(layer "F.Fab")
		)
		(fp_line
			(start 0.201 0)
			(end 0.201 -0.202)
			(stroke
				(width 0.15)
				(type solid)
			)
			(layer "F.Fab")
		)
		(fp_line
			(start -0.101 0)
			(end 0.201 0.2)
			(stroke
				(width 0.15)
				(type solid)
			)
			(layer "F.Fab")
		)
		(fp_line
			(start -0.199 0)
			(end -0.597 0)
			(stroke
				(width 0.15)
				(type solid)
			)
			(layer "F.Fab")
		)
		(fp_line
			(start 0.201 0.2)
			(end 0.201 0)
			(stroke
				(width 0.15)
				(type solid)
			)
			(layer "F.Fab")
		)
		(fp_line
			(start -0.199 0.2)
			(end -0.199 0.1)
			(stroke
				(width 0.15)
				(type solid)
			)
			(layer "F.Fab")
		)
		(fp_rect
			(start 0.848 0.4)
			(end -0.85 -0.402)
			(stroke
				(width 0.15)
				(type solid)
			)
			(fill no)
			(layer "F.Fab")
		)
		(fp_text user "License: Apache-2.0"
			(at -1.4224 3.599 90)
			(layer "F.Fab")
			(effects
				(font
					(size 0.7 0.7)
					(thickness 0.15)
				)
				(justify left bottom)
			)
		)
		(fp_text user "Author: Antmicro"
			(at -1.4224 4.799 90)
			(layer "F.Fab")
			(effects
				(font
					(size 0.7 0.7)
					(thickness 0.15)
				)
				(justify left bottom)
			)
		)
		(fp_text user "${REFERENCE}"
			(at -1.4224 5.999 90)
			(layer "F.Fab")
			(effects
				(font
					(size 0.7 0.7)
					(thickness 0.15)
				)
				(justify left bottom)
			)
		)
		(pad "1" smd roundrect
			(at -0.7 0 270)
			(size 0.8 1)
			(layers "F.Cu" "F.Mask" "F.Paste")
			(roundrect_rratio 0.2)
			(net 1 "GND")
			(pinfunction "C")
			(pintype "passive")
		)
		(pad "2" smd roundrect
			(at 0.7 0 270)
			(size 0.8 1)
			(layers "F.Cu" "F.Mask" "F.Paste")
			(roundrect_rratio 0.2)
			(net 246 "Net-(D7-A)")
			(pinfunction "A")
			(pintype "passive")
		)
	)
	(footprint "antmicro-footprints:TP_SMD_0.75mm"
		(layer "F.Cu")
		(at 106.25 90.37 -90)
		(property "Reference" "TP16"
			(at -2.92 0.34 90)
			(layer "F.SilkS")
			(effects
				(font
					(size 0.65 0.65)
					(thickness 0.15)
				)
				(justify right top)
			)
		)
		(property "Value" "TP_0.75mm_SMD"
			(at 0 1.2 90)
			(layer "F.Fab")
			(hide yes)
			(effects
				(font
					(size 0.7 0.7)
					(thickness 0.15)
				)
				(justify right top)
			)
		)
		(property "Description" "SMT test point"
			(at 0 0 90)
			(layer "F.Fab")
			(hide yes)
			(effects
				(font
					(size 1.27 1.27)
					(thickness 0.15)
				)
			)
		)
		(property "Author" "Antmicro"
			(at 165.8 346.6 0)
			(layer "F.Fab")
			(hide yes)
			(effects
				(font
					(size 1 1)
					(thickness 0.15)
				)
			)
		)
		(property "License" "Apache-2.0"
			(at 165.8 346.6 0)
			(layer "F.Fab")
			(hide yes)
			(effects
				(font
					(size 1 1)
					(thickness 0.15)
				)
			)
		)
		(property "MPN" ""
			(at 165.8 346.6 0)
			(layer "F.Fab")
			(hide yes)
			(effects
				(font
					(size 1 1)
					(thickness 0.15)
				)
			)
		)
		(property "Manufacturer" ""
			(at 165.8 346.6 0)
			(layer "F.Fab")
			(hide yes)
			(effects
				(font
					(size 1 1)
					(thickness 0.15)
				)
			)
		)
		(sheetname "/FPGA/")
		(sheetfile "fpga.kicad_sch")
		(attr exclude_from_pos_files)
		(fp_circle
			(center 0 0)
			(end 0.475 0)
			(stroke
				(width 0.05)
				(type default)
			)
			(fill no)
			(layer "F.CrtYd")
		)
		(fp_text user "License: Apache-2.0"
			(at -0.4 5.101 90)
			(layer "F.Fab")
			(effects
				(font
					(size 0.7 0.7)
					(thickness 0.15)
				)
				(justify right top)
			)
		)
		(fp_text user "Author: Antmicro"
			(at -0.4 3.901 90)
			(layer "F.Fab")
			(effects
				(font
					(size 0.7 0.7)
					(thickness 0.15)
				)
				(justify right top)
			)
		)
		(fp_text user "${REFERENCE}"
			(at -0.4 2.7 90)
			(layer "F.Fab")
			(effects
				(font
					(size 0.7 0.7)
					(thickness 0.15)
				)
				(justify right top)
			)
		)
		(pad "1" smd circle
			(at 0 0 270)
			(size 0.75 0.75)
			(layers "F.Cu" "F.Mask")
			(net 301 "Net-(U18-SO{slash}IO1)")
			(pinfunction "1")
			(pintype "passive")
		)
	)
	(footprint "antmicro-footprints:R_0805_2012Metric"
		(layer "F.Cu")
		(at 161.19 57.54 90)
		(property "Reference" "R40"
			(at 0.26 -1.11 90)
			(layer "F.SilkS")
			(effects
				(font
					(size 0.65 0.65)
					(thickness 0.15)
				)
				(justify left bottom)
			)
		)
		(property "Value" "R_0R_0805"
			(at 0 1.8 90)
			(layer "F.Fab")
			(hide yes)
			(effects
				(font
					(size 0.7 0.7)
					(thickness 0.15)
				)
				(justify left bottom)
			)
		)
		(property "Datasheet" "https://www.vishay.com/docs/20035/dcrcwe3.pdf"
			(at 0 0 90)
			(layer "F.Fab")
			(hide yes)
			(effects
				(font
					(size 1.27 1.27)
					(thickness 0.15)
				)
			)
		)
		(property "Description" "Zero Ohm Resistor, Jumper, 0805 [2012 Metric], Thick Film, 125 mW, 2.5 A, Surface Mount Device"
			(at 0 0 90)
			(layer "F.Fab")
			(hide yes)
			(effects
				(font
					(size 1.27 1.27)
					(thickness 0.15)
				)
			)
		)
		(property "Author" "Antmicro"
			(at 218.79 -103.59 0)
			(layer "F.Fab")
			(hide yes)
			(effects
				(font
					(size 1 1)
					(thickness 0.15)
				)
			)
		)
		(property "Current" "2.5A"
			(at 218.79 -103.59 0)
			(layer "F.Fab")
			(hide yes)
			(effects
				(font
					(size 1 1)
					(thickness 0.15)
				)
			)
		)
		(property "License" "Apache-2.0"
			(at 218.79 -103.59 0)
			(layer "F.Fab")
			(hide yes)
			(effects
				(font
					(size 1 1)
					(thickness 0.15)
				)
			)
		)
		(property "MPN" "CRCW08050000Z0EA"
			(at 218.79 -103.59 0)
			(layer "F.Fab")
			(hide yes)
			(effects
				(font
					(size 1 1)
					(thickness 0.15)
				)
			)
		)
		(property "Manufacturer" "Vishay"
			(at 218.79 -103.59 0)
			(layer "F.Fab")
			(hide yes)
			(effects
				(font
					(size 1 1)
					(thickness 0.15)
				)
			)
		)
		(property "Tolerance" "~"
			(at 218.79 -103.59 0)
			(layer "F.Fab")
			(hide yes)
			(effects
				(font
					(size 1 1)
					(thickness 0.15)
				)
			)
		)
		(property "Val" "0R"
			(at 218.79 -103.59 0)
			(layer "F.Fab")
			(hide yes)
			(effects
				(font
					(size 1 1)
					(thickness 0.15)
				)
			)
		)
		(sheetname "/Power Supply/")
		(sheetfile "supply.kicad_sch")
		(attr smd)
		(fp_line
			(start -0.3 -0.701)
			(end 0.298 -0.701)
			(stroke
				(width 0.15)
				(type solid)
			)
			(layer "F.SilkS")
		)
		(fp_line
			(start -0.32 0.699)
			(end 0.28 0.699)
			(stroke
				(width 0.15)
				(type solid)
			)
			(layer "F.SilkS")
		)
		(fp_rect
			(start 1.95 -0.9)
			(end -1.95 0.9)
			(stroke
				(width 0.05)
				(type default)
			)
			(fill no)
			(layer "F.CrtYd")
		)
		(fp_line
			(start -0.951 -0.682)
			(end 0.949 -0.682)
			(stroke
				(width 0.15)
				(type solid)
			)
			(layer "F.Fab")
		)
		(fp_line
			(start 0.949 -0.677)
			(end 0.949 0.675)
			(stroke
				(width 0.15)
				(type solid)
			)
			(layer "F.Fab")
		)
		(fp_line
			(start -0.951 -0.677)
			(end -0.951 0.675)
			(stroke
				(width 0.15)
				(type solid)
			)
			(layer "F.Fab")
		)
		(fp_line
			(start -0.951 0.68)
			(end 0.949 0.68)
			(stroke
				(width 0.15)
				(type solid)
			)
			(layer "F.Fab")
		)
		(fp_text user "License: Apache-2.0"
			(at -1.9 5.75 90)
			(layer "F.Fab")
			(effects
				(font
					(size 0.7 0.7)
					(thickness 0.15)
				)
				(justify left bottom)
			)
		)
		(fp_text user "Author: Antmicro"
			(at -1.9 4.4 90)
			(layer "F.Fab")
			(effects
				(font
					(size 0.7 0.7)
					(thickness 0.15)
				)
				(justify left bottom)
			)
		)
		(fp_text user "${REFERENCE}"
			(at -1.9 3.1 90)
			(layer "F.Fab")
			(effects
				(font
					(size 0.7 0.7)
					(thickness 0.15)
				)
				(justify left bottom)
			)
		)
		(pad "1" smd roundrect
			(at -1.1 0 90)
			(size 1.2 1.3)
			(layers "F.Cu" "F.Mask" "F.Paste")
			(roundrect_rratio 0.25)
			(net 275 "/Power Supply/3V3_OUT")
			(pintype "passive")
		)
		(pad "2" smd roundrect
			(at 1.1 0 90)
			(size 1.2 1.3)
			(layers "F.Cu" "F.Mask" "F.Paste")
			(roundrect_rratio 0.25)
			(net 2 "+3V3")
			(pintype "passive")
		)
	)
)
